# S9S_MB_2U (Grand Teton) — schematic parts with pin connectivity, parts 3159–3224 of 6093; source: Cadence DE-HDL packaged netlist (pstxprt.dat, pstxnet.dat, pstchip.dat)

Q16  MOSFET_NCH_DUAL  PJT138K IC  pkg SOT363XD  page 235
  1  S1  BI  = GND
  2  G1  BI  = FM_SMB_PEHPCPU1_PCIE_ALERT_R_N
  3  D2  BI  = FM_PEHPCPU1_ALERT_N
  4  S2  BI  = GND
  5  G2  BI  = FM_SMB_CPU1_ALERT_R1
  6  D1  BI  = FM_SMB_CPU1_ALERT_R1

Q33  MOSFET_NCH_GDS_ESD_PROTECTED  2N7002K IC  pkg SOT23_GDSXC  page 218
  D  D  BI  = LED_CPU_RMCA_CATERR
  G  G  IN  = CPU_RMCA_CATERR_LVT3_N
  S  S  BI  = LED_CPU_RMCA_CATERR_R

Q34  MOSFET_NCH_GDS_ESD_PROTECTED  2N7002K IC  pkg SOT23_GDSXC  page 185
  D  D  BI  = RST_RTCRST_N
  G  G  IN  = RST_PFR_OVR_RTC
  S  S  BI  = GND

Q35  MOSFET_NCH_GDS_ESD_PROTECTED  2N7002K IC  pkg SOT23_GDSXC  page 185
  D  D  BI  = RST_SRTCRST_N
  G  G  IN  = RST_PFR_OVR_SRTC
  S  S  BI  = GND

Q37  MOSFET_NCH_DUAL  PJT138K IC  pkg SOT363XD  page 260
  1  S1  BI  = GND
  2  G1  BI  = VR_P5V_EN
  3  D2  BI  = VR_P5V_EN_D_R1
  4  S2  BI  = GND
  5  G2  BI  = VR_P5V_EN_N
  6  D1  BI  = VR_P5V_EN_N

Q39  MOSFET_NCH_GDS_ESD_PROTECTED  2N7002K IC  pkg SOT23_GDSXC  page 242
  D  D  BI  = P12V_SCM_EN
  G  G  IN  = FM_SCM_PRSNT1_R_N
  S  S  BI  = GND

Q46  MOSFET_NCH_GDS_ESD_PROTECTED  2N7002K IC  pkg SOT23_GDSXC  page 191
  D  D  BI  = E1S_0_PRSNT
  G  G  IN  = E1S_0_PRSNT_N
  S  S  BI  = GND

Q50  MOSFET_NCH_DUAL  PJT138K IC  pkg SOT363XD  page 213
  1  S1  BI  = GND
  2  G1  BI  = PWRGD_P5V_AUX
  3  D2  BI  = PWRGD_P5V_AUX_R2
  4  S2  BI  = GND
  5  G2  BI  = PWRGD_P5V_AUX_R1
  6  D1  BI  = PWRGD_P5V_AUX_R1

Q52  MOSFET_NCH_GDS_ESD_PROTECTED  2N7002K IC  pkg SOT23_GDSXC  page 244
  D  D  BI  = FM_COMP_P3V3_AUX_VIN_R
  G  G  IN  = PWRGD_P3V3_AUX_R2
  S  S  BI  = GND

Q53  MOSFET_NCH_GDS_ESD_PROTECTED  2N7002K IC  pkg SOT23_GDSXC  page 244
  D  D  BI  = PWRGD_P3V3_AUX_R2
  G  G  IN  = PWRGD_P3V3_AUX
  S  S  BI  = GND

Q54  MOSFET_NCH_GDS_ESD_PROTECTED  2N7002K IC  pkg SOT23_GDSXC  page 247
  D  D  BI  = P12V_AUX_BLEEDING
  G  G  IN  = FM_P12V_HSC_EN_R_N
  S  S  BI  = GND

Q56  MOSFET_NCH_1D3S  PSMNR58-30YLH IC  pkg SOT1023  page 260
  1  \1\  BI  = P3V3
  2  \2\  BI  = P3V3
  3  \3\  BI  = P3V3
  4  \4\  IN  = PWRGD_P5V_ISO_R
  5  \5\  BI  = P3V3_AUX

Q57  MOSFET_NCH_1D3S  PSMNR58-30YLH IC  pkg SOT1023  page 260
  1  \1\  BI  = P5V
  2  \2\  BI  = P5V
  3  \3\  BI  = P5V
  4  \4\  IN  = VR_P5V_EN_D_R
  5  \5\  BI  = P5V_AUX

Q67  MOSFET_NCH_DUAL  PJT138K IC  pkg SOT363XD  page 148
  1  S1  BI  = GND
  2  G1  BI  = BIC_MONITER
  3  D2  BI  = BIC_MONITER_ISO
  4  S2  BI  = GND
  5  G2  BI  = BIC_MONITER_N
  6  D1  BI  = BIC_MONITER_N

Q69  MOSFET_NCH_DUAL  PJT138K IC  pkg SOT363XD  page 148
  1  S1  BI  = GND
  2  G1  BI  = RST_BMC_FROM_SWB_N
  3  D2  BI  = RST_BMC_FROM_SWB_ISO_N
  4  S2  BI  = GND
  5  G2  BI  = RST_BMC_FROM_SWB
  6  D1  BI  = RST_BMC_FROM_SWB

Q70  MOSFET_NCH_DUAL  PJT138K IC  pkg SOT363XD  page 148
  1  S1  BI  = GND
  2  G1  BI  = FM_SWB_BIC_READY_N
  3  D2  BI  = FM_SWB_BIC_READY_ISO_N
  4  S2  BI  = GND
  5  G2  BI  = FM_SWB_BIC_READY
  6  D1  BI  = FM_SWB_BIC_READY

Q71  MOSFET_NCH_DUAL  PJT138K IC  pkg SOT363XD  page 148
  1  S1  BI  = GND
  2  G1  BI  = FM_SWB_PWRGD
  3  D2  BI  = FM_SWB_PWRGD_ISO
  4  S2  BI  = GND
  5  G2  BI  = FM_SWB_PWRGD_N
  6  D1  BI  = FM_SWB_PWRGD_N

Q72  MOSFET_NCH_DUAL  PJT138K IC  pkg SOT363XD  page 148
  1  S1  BI  = GND
  2  G1  BI  = FM_GPU_PWRGD
  3  D2  BI  = FM_GPU_PWRGD_ISO
  4  S2  BI  = GND
  5  G2  BI  = FM_GPU_PWRGD_N
  6  D1  BI  = FM_GPU_PWRGD_N

Q74  MOSFET_NCH_DUAL  PJT138K IC  pkg SOT363XD  page 148
  1  S1  BI  = GND
  2  G1  BI  = FM_SMB_2_ALERT_GPU_N
  3  D2  BI  = FM_SMB_2_ALERT_GPU_ISO_N
  4  S2  BI  = GND
  5  G2  BI  = FM_SMB_2_ALERT_GPU
  6  D1  BI  = FM_SMB_2_ALERT_GPU

Q75  MOSFET_NCH_DUAL  PJT138K IC  pkg SOT363XD  page 148
  1  S1  BI  = GND
  2  G1  BI  = FM_SMB_1_ALERT_GPU_N
  3  D2  BI  = FM_SMB_1_ALERT_GPU_ISO_N
  4  S2  BI  = GND
  5  G2  BI  = FM_SMB_1_ALERT_GPU
  6  D1  BI  = FM_SMB_1_ALERT_GPU

Q76  MOSFET_NCH_DUAL  PJT138K IC  pkg SOT363XD  page 252
  1  S1  BI  = GND
  2  G1  BI  = PWRGD_P1V8_PCH_AUX
  3  D2  BI  = LED_PWRGD_P1V05_PCH_AUX_D
  4  S2  BI  = GND
  5  G2  BI  = PWRGD_P1V05_PCH_AUX
  6  D1  BI  = LED_PWRGD_P1V8_PCH_AUX_D

Q77  MOSFET_NCH_DUAL  PJT138K IC  pkg SOT363XD  page 252
  1  S1  BI  = GND
  2  G1  BI  = RST_RSMRST_PLD_R_N
  3  D2  BI  = LED_FM_PCH_SLP_S4_N_D
  4  S2  BI  = GND
  5  G2  BI  = FM_PCH_SLP_S4_N
  6  D1  BI  = LED_RST_RSMRST_PLD_R_N_D

Q78  MOSFET_NCH_DUAL  PJT138K IC  pkg SOT363XD  page 252
  1  S1  BI  = GND
  2  G1  BI  = FM_PCH_SLP_S3_N
  3  D2  BI  = LED_PWRGD_PS_PWROK_PLD_D
  4  S2  BI  = GND
  5  G2  BI  = PWRGD_PS_PWROK_PLD
  6  D1  BI  = LED_FM_PCH_SLP_S3_N_D

Q79  MOSFET_NCH_DUAL  PJT138K IC  pkg SOT363XD  page 253
  1  S1  BI  = GND
  2  G1  BI  = PWRGD_PVCCD_HV_CPU0
  3  D2  BI  = LED_PWRGD_PVPP_HBM_CPU0_D
  4  S2  BI  = GND
  5  G2  BI  = PWRGD_PVPP_HBM_CPU0
  6  D1  BI  = LED_PWRGD_PVCCD_HV_CPU0_D

Q80  MOSFET_NCH_DUAL  PJT138K IC  pkg SOT363XD  page 253
  1  S1  BI  = GND
  2  G1  BI  = PWRGD_PVCCFA_EHV_CPU0
  3  D2  BI  = LED_PWRGD_PVCCFA_EHV_FIVRA_CP_1
  4  S2  BI  = GND
  5  G2  BI  = PWRGD_PVCCFA_EHV_FIVRA_CPU0
  6  D1  BI  = LED_PWRGD_PVCCFA_EHV_CPU0_D

Q81  MOSFET_NCH_DUAL  PJT138K IC  pkg SOT363XD  page 253
  1  S1  BI  = GND
  2  G1  BI  = PWRGD_PVCCINFAON_CPU0
  3  D2  BI  = LED_PWRGD_PVNN_MAIN_CPU0_D
  4  S2  BI  = GND
  5  G2  BI  = PWRGD_PVNN_MAIN_CPU0
  6  D1  BI  = LED_PWRGD_PVCCINFAON_CPU0_D

Q83  MOSFET_NCH_DUAL  PJT138K IC  pkg SOT363XD  page 253
  1  S1  BI  = GND
  2  G1  BI  = PWRGD_PVCCIN_CPU0
  3  D2  BI  = LED_PWRGD_PVCCIN_CPU1_D
  4  S2  BI  = GND
  5  G2  BI  = PWRGD_PVCCIN_CPU1
  6  D1  BI  = LED_PWRGD_PVCCIN_CPU0_D

Q84  MOSFET_NCH_DUAL  PJT138K IC  pkg SOT363XD  page 254
  1  S1  BI  = GND
  2  G1  BI  = PWRGD_PVCCD_HV_CPU1
  3  D2  BI  = LED_PWRGD_PVPP_HBM_CPU1_D
  4  S2  BI  = GND
  5  G2  BI  = PWRGD_PVPP_HBM_CPU1
  6  D1  BI  = LED_PWRGD_PVCCD_HV_CPU1_D

Q85  MOSFET_NCH_DUAL  PJT138K IC  pkg SOT363XD  page 254
  1  S1  BI  = GND
  2  G1  BI  = PWRGD_PVCCFA_EHV_CPU1
  3  D2  BI  = LED_PWRGD_PVCCFA_EHV_FIVRA_CP_2
  4  S2  BI  = GND
  5  G2  BI  = PWRGD_PVCCFA_EHV_FIVRA_CPU1
  6  D1  BI  = LED_PWRGD_PVCCFA_EHV_CPU1_D

Q86  MOSFET_NCH_DUAL  PJT138K IC  pkg SOT363XD  page 254
  1  S1  BI  = GND
  2  G1  BI  = PWRGD_PVCCINFAON_CPU1
  3  D2  BI  = LED_PWRGD_PVNN_MAIN_CPU1_D
  4  S2  BI  = GND
  5  G2  BI  = PWRGD_PVNN_MAIN_CPU1
  6  D1  BI  = LED_PWRGD_PVCCINFAON_CPU1_D

Q87  MOSFET_NCH_DUAL  PJT138K IC  pkg SOT363XD  page 255
  1  S1  BI  = GND
  2  G1  BI  = PWRGD_PCH_PWROK_R
  3  D2  BI  = LED_PWRGD_SYS_PWROK_R_D
  4  S2  BI  = GND
  5  G2  BI  = PWRGD_SYS_PWROK_R
  6  D1  BI  = LED_PWRGD_PCH_PWROK_R_D

Q88  MOSFET_NCH_DUAL  PJT138K IC  pkg SOT363XD  page 255
  1  S1  BI  = GND
  2  G1  BI  = PWRGD_CPUPWRGD_LVC2_R1
  3  D2  BI  = LED_RST_PLTRST_N_D
  4  S2  BI  = GND
  5  G2  BI  = RST_PLTRST_N
  6  D1  BI  = LED_PWRGD_CPUPWRGD_GTL_D

Q95  MOSFET_NCH_DUAL  PJT138K IC  pkg SOT363XD  page 190
  1  S1  BI  = GND
  2  G1  BI  = HDD_ACTIVITY_BUF
  3  D2  BI  = NC_Q95_D2
  4  S2  BI  = NC_Q95_S2
  5  G2  BI  = NC_Q95_G2
  6  D1  BI  = HDD_ACTIVITY_BUF_N

Q96  MOSFET_NCH_DUAL  PJT138K IC  pkg SOT363XD  page 148
  1  S1  BI  = GND
  2  G1  BI  = GPU_FPGA_READY
  3  D2  BI  = GPU_FPGA_READY_ISO
  4  S2  BI  = GND
  5  G2  BI  = GPU_FPGA_READY_N
  6  D1  BI  = GPU_FPGA_READY_N

Q97  MOSFET_NCH_DUAL  NX6008NBKS IC  pkg SOT363XB  page 256
  1  S1  BI  = GND
  2  G1  BI  = RST_PLD_CPU0_DRAM_EF_N
  3  D2  BI  = LED_RST_PLD_CPU0_DRAM_GH_N_D
  4  S2  BI  = GND
  5  G2  BI  = RST_PLD_CPU0_DRAM_GH_N
  6  D1  BI  = LED_RST_PLD_CPU0_DRAM_EF_N_D

Q98  MOSFET_NCH_DUAL  NX6008NBKS IC  pkg SOT363XB  page 256
  1  S1  BI  = GND
  2  G1  BI  = RST_PLD_CPU0_DRAM_AB_N
  3  D2  BI  = LED_RST_PLD_CPU0_DRAM_CD_N_D
  4  S2  BI  = GND
  5  G2  BI  = RST_PLD_CPU0_DRAM_CD_N
  6  D1  BI  = LED_RST_PLD_CPU0_DRAM_AB_N_D

Q99  MOSFET_NCH_DUAL  NX6008NBKS IC  pkg SOT363XB  page 256
  1  S1  BI  = GND
  2  G1  BI  = RST_PLD_CPU1_DRAM_CD_N
  6  D1  BI  = LED_RST_PLD_CPU1_DRAM_CD_N_D

Q100  MOSFET_NCH_DUAL  NX6008NBKS IC  pkg SOT363XB  page 256
  1  S1  BI  = GND
  2  G1  BI  = RST_PLD_CPU1_DRAM_EF_N
  3  D2  BI  = LED_RST_PLD_CPU1_DRAM_GH_N_D
  4  S2  BI  = GND
  5  G2  BI  = RST_PLD_CPU1_DRAM_GH_N
  6  D1  BI  = LED_RST_PLD_CPU1_DRAM_EF_N_D

Q101  MOSFET_NCH_DUAL  PJT138K IC  pkg SOT363XD  page 147
  1  S1  BI  = GND
  2  G1  BI  = GPU_FPGA_THERM_OVERT_N
  3  D2  BI  = GPU_FPGA_THERM_OVERT_ISO_N
  4  S2  BI  = GND
  5  G2  BI  = GPU_FPGA_THERM_OVERT
  6  D1  BI  = GPU_FPGA_THERM_OVERT

Q102  MOSFET_NCH_DUAL  PJT138K IC  pkg SOT363XD  page 147
  1  S1  BI  = GND
  2  G1  BI  = GPU_BASE_HMC_READY
  3  D2  BI  = GPU_BASE_HMC_READY_ISO
  4  S2  BI  = GND
  5  G2  BI  = GPU_BASE_HMC_READY_N
  6  D1  BI  = GPU_BASE_HMC_READY_N

Q103  MOSFET_NCH_DUAL  PJT138K IC  pkg SOT363XD  page 147
  1  S1  BI  = GND
  2  G1  BI  = GPU_HMC_PRSNT_N
  3  D2  BI  = GPU_HMC_PRSNT_ISO_N
  4  S2  BI  = GND
  5  G2  BI  = GPU_HMC_PRSNT
  6  D1  BI  = GPU_HMC_PRSNT

Q104  MOSFET_NCH_DUAL  PJT138K IC  pkg SOT363XD  page 147
  1  S1  BI  = GND
  2  G1  BI  = GPU_FPGA_OVERT_N
  3  D2  BI  = GPU_FPGA_OVERT_ISO_N
  4  S2  BI  = GND
  5  G2  BI  = GPU_FPGA_OVERT
  6  D1  BI  = GPU_FPGA_OVERT

Q105  MOSFET_NCH_DUAL  NX6008NBKS IC  pkg SOT363XB  page 256
  1  S1  BI  = GND
  2  G1  BI  = RST_PLD_CPU1_DRAM_AB_N
  6  D1  BI  = LED_RST_PLD_CPU1_DRAM_AB_N_D

Q106  MOSFET_NCH_DUAL  PJT138K IC  pkg SOT363XD  page 147
  1  S1  BI  = GND
  2  G1  BI  = GPU_WP_HW_CTRL_N
  6  D1  BI  = GPU_WP_HW_CTRL_ISO

Q107  MOSFET_NCH_DUAL  PJT138K IC  pkg SOT363XD  page 147
  1  S1  BI  = GND
  2  G1  BI  = GPU_PRSNT_N
  3  D2  BI  = GPU_PRSNT_N_ISO
  4  S2  BI  = GND
  5  G2  BI  = GPU_PRSNT
  6  D1  BI  = GPU_PRSNT

Q108  MOSFET_NCH_DUAL  PJT138K IC  pkg SOT363XD  page 147
  1  S1  BI  = GND
  2  G1  BI  = GPU_FPGA_EROT_FATALERR_N
  3  D2  BI  = GPU_FPGA_EROT_FATALERR_ISO_N
  4  S2  BI  = GND
  5  G2  BI  = GPU_FPGA_EROT_FATALERR
  6  D1  BI  = GPU_FPGA_EROT_FATALERR

Q118  MOSFET_NCH_DUAL  PJT138K EMPTY  pkg SOT363XD  page 162
  1  S1  BI  = GND
  2  G1  BI  = P12V_OCP_EN_2_R
  3  D2  BI  = P12V_OCP_UV_2_R
  4  S2  BI  = GND
  5  G2  BI  = P12V_OCP_2_EN_G
  6  D1  BI  = P12V_OCP_2_EN_G

Q119  MOSFET_NCH_DUAL  PJT138K IC  pkg SOT363XD  page 162
  1  S1  BI  = GND
  2  G1  BI  = P3V3_OCP_EN_2_R
  3  D2  BI  = P3V3_OCP_UV_2_R1
  4  S2  BI  = GND
  5  G2  BI  = P3V3_OCP_2_EN_G
  6  D1  BI  = P3V3_OCP_2_EN_G

Q123  MOSFET_NCH_DUAL  PJT138K EMPTY  pkg SOT363XD  page 156
  1  S1  BI  = GND
  2  G1  BI  = P12V_OCP_EN_1_R
  3  D2  BI  = P12V_OCP_UV_1_R
  4  S2  BI  = GND
  5  G2  BI  = P12V_OCP_1_EN_G
  6  D1  BI  = P12V_OCP_1_EN_G

Q124  MOSFET_NCH_DUAL  PJT138K IC  pkg SOT363XD  page 156
  1  S1  BI  = GND
  2  G1  BI  = P3V3_OCP_EN_1_R
  3  D2  BI  = P3V3_OCP_UV_1_R1
  4  S2  BI  = GND
  5  G2  BI  = P3V3_OCP_1_EN_G
  6  D1  BI  = P3V3_OCP_1_EN_G

Q125  MOSFET_NCH_DUAL  PJT138K EMPTY  pkg SOT363XD  page 242
  1  S1  BI  = GND
  2  G1  BI  = P12V_SCM_EN_R
  3  D2  BI  = P12V_SCM_UV_R
  4  S2  BI  = GND
  5  G2  BI  = P12V_SCM_EN_G
  6  D1  BI  = P12V_SCM_EN_G

Q126  MOSFET_NCH_DUAL  PJT138K IC  pkg SOT363XD  page 192
  1  S1  BI  = GND
  2  G1  BI  = P3V3_E1S_EN_1_R
  3  D2  BI  = P3V3_E1S_UV_0_R
  4  S2  BI  = GND
  5  G2  BI  = P3V3_E1S_0_EN_G
  6  D1  BI  = P3V3_E1S_0_EN_G

Q127  MOSFET_NCH_DUAL  PJT138K EMPTY  pkg SOT363XD  page 192
  1  S1  BI  = GND
  2  G1  BI  = P12V_E1S_EN_0_R
  3  D2  BI  = P12V_E1S_UV_0_R
  4  S2  BI  = GND
  5  G2  BI  = P12V_E1S_0_EN_G
  6  D1  BI  = P12V_E1S_0_EN_G

Q128  MOSFET_NCH_DUAL  PJT138K IC  pkg SOT363XD  page 146
  1  S1  BI  = GND
  2  G1  BI  = GPU_3V3IO_RSVD0_FFU
  3  D2  BI  = GPU_3V3IO_RSVD0_FFU_ISO
  4  S2  BI  = GND
  5  G2  BI  = GPU_3V3IO_RSVD0_FFU_N
  6  D1  BI  = GPU_3V3IO_RSVD0_FFU_N

Q129  MOSFET_NCH_DUAL  PJT138K IC  pkg SOT363XD  page 146
  1  S1  BI  = GND
  2  G1  BI  = GPU_3V3IO_RSVD5_FFU
  3  D2  BI  = GPU_3V3IO_RSVD5_FFU_ISO
  4  S2  BI  = GND
  5  G2  BI  = GPU_3V3IO_RSVD5_FFU_N
  6  D1  BI  = GPU_3V3IO_RSVD5_FFU_N

Q130  MOSFET_NCH_DUAL  PJT138K IC  pkg SOT363XD  page 146
  1  S1  BI  = GND
  2  G1  BI  = GPU_3V3IO_RSVD3_FFU
  3  D2  BI  = GPU_3V3IO_RSVD3_FFU_ISO
  4  S2  BI  = GND
  5  G2  BI  = GPU_3V3IO_RSVD3_FFU_N
  6  D1  BI  = GPU_3V3IO_RSVD3_FFU_N

Q131  MOSFET_NCH_DUAL  PJT138K IC  pkg SOT363XD  page 146
  1  S1  BI  = GND
  2  G1  BI  = GPU_3V3IO_RSVD1_FFU
  3  D2  BI  = GPU_3V3IO_RSVD1_FFU_ISO
  4  S2  BI  = GND
  5  G2  BI  = GPU_3V3IO_RSVD1_FFU_N
  6  D1  BI  = GPU_3V3IO_RSVD1_FFU_N

Q132  MOSFET_NCH_DUAL  PJT138K IC  pkg SOT363XD  page 146
  1  S1  BI  = GND
  2  G1  BI  = PRSNT_CABLE_GPU_B3_N
  3  D2  BI  = PRSNT_CABLE_GPU_B3_ISO_N
  4  S2  BI  = GND
  5  G2  BI  = PRSNT_CABLE_GPU_B3
  6  D1  BI  = PRSNT_CABLE_GPU_B3

Q133  MOSFET_NCH_DUAL  PJT138K IC  pkg SOT363XD  page 146
  1  S1  BI  = GND
  2  G1  BI  = PRSNT_CABLE_GPU_A2_N
  3  D2  BI  = PRSNT_CABLE_GPU_A2_ISO_N
  4  S2  BI  = GND
  5  G2  BI  = PRSNT_CABLE_GPU_A2
  6  D1  BI  = PRSNT_CABLE_GPU_A2

Q134  MOSFET_NCH_DUAL  PJT138K IC  pkg SOT363XD  page 146
  1  S1  BI  = GND
  2  G1  BI  = PRSNT_CABLE_GPU_A1_N
  3  D2  BI  = PRSNT_CABLE_GPU_A1_ISO_N
  4  S2  BI  = GND
  5  G2  BI  = PRSNT_CABLE_GPU_A1
  6  D1  BI  = PRSNT_CABLE_GPU_A1

Q135  MOSFET_NCH_DUAL  PJT138K IC  pkg SOT363XD  page 145
  1  S1  BI  = GND
  2  G1  BI  = GPU_3V3IO_RSVD1
  3  D2  BI  = GPU_3V3IO_RSVD1_ISO
  4  S2  BI  = GND
  5  G2  BI  = GPU_3V3IO_RSVD1_N
  6  D1  BI  = GPU_3V3IO_RSVD1_N

Q136  MOSFET_NCH_DUAL  PJT138K IC  pkg SOT363XD  page 145
  1  S1  BI  = GND
  2  G1  BI  = GPU_3V3IO_RSVD4
  3  D2  BI  = GPU_3V3IO_RSVD4_ISO
  4  S2  BI  = GND
  5  G2  BI  = GPU_3V3IO_RSVD4_N
  6  D1  BI  = GPU_3V3IO_RSVD4_N

Q137  MOSFET_NCH_DUAL  PJT138K IC  pkg SOT363XD  page 145
  1  S1  BI  = GND
  2  G1  BI  = GPU_3V3IO_RSVD3
  3  D2  BI  = GPU_3V3IO_RSVD3_ISO
  4  S2  BI  = GND
  5  G2  BI  = GPU_3V3IO_RSVD3_N
  6  D1  BI  = GPU_3V3IO_RSVD3_N

Q138  BC847BPN  IC  pkg SOT363XB  page 121
  1  E1  BI  = GND
  2  B1  IN  = H_CPU0_THERMTRIP_R_N
  3  C2  BI  = H_CPU0_THERMTRIP_N
  4  E2  BI  = PVNN_TERM_CPU0
  5  B2  IN  = H_CPU0_THERMTRIP_VT_R_N
  6  C1  BI  = H_CPU0_THERMTRIP_VT_N

Q139  BC847BPN  IC  pkg SOT363XB  page 121
  1  E1  BI  = GND
  2  B1  IN  = H_CPU1_THERMTRIP_R_N
  3  C2  BI  = H_CPU1_THERMTRIP_N
  4  E2  BI  = PVNN_TERM_CPU1
  5  B2  IN  = H_CPU1_THERMTRIP_VT_R_N
  6  C1  BI  = H_CPU1_THERMTRIP_VT_N

Q140  BC847BPN  IC  pkg SOT363XB  page 123
  1  E1  BI  = GND
  2  B1  IN  = H_CPU1_MEMTRIP_R
  3  C2  BI  = H_CPU1_MEMTRIP
  4  E2  BI  = PVNN_TERM_CPU1
  5  B2  IN  = H_CPU1_MEMTRIP_OUT_VT_R_N
  6  C1  BI  = H_CPU1_MEMTRIP_VT_N
